# S9S_MB_2U (Grand Teton) — schematic netlist excerpt (pin names and nets, part order shuffled) for the footprints in the layout excerpt that follows; sources: Cadence DE-HDL packaged netlist, KiCad conversion of 03242023_DA0F0TMBIJ0_F0T_Motherboard_J_brd_V01_OCP.brd

R4710  Q_RES  4.7K 5% CHIP  pkg 0402LF  page 255 : A = P3V3_AUX ; B = LED_P12V_SCM_FAULT_D1
PR3965  Q_RES  15K 1% CHIP  pkg 0402LF  page 192 : A = P3V3_E1S_OV_0 ; B = GND
C1793  Q_CAP_DIFFBUS  DIFF BUS_0.22UF 6.3V 20% X6S  pkg C0201  page 175 : \1\ = P5E_CPU0_PE4_TX_C_DP<9> ; \2\ = P5E_CPU0_PE4_TX_DP<9>

(kicad_pcb
	(version 20260206)
	(generator "pcbnew")
	(generator_version "10.0")
	(general
		(thickness 1.6)
		(legacy_teardrops no)
	)
	(paper "A4")
	(title_block
		(title "03242023_DA0F0TMBIJ0_F0T_Motherboard_J_brd_V01_OCP.brd")
		(comment 1 "Grand Teton / footprints 886-888 of 6105")
	)
	(layers
		(0 "F.Cu" signal "TOP")
		(4 "In1.Cu" signal "GND")
		(6 "In2.Cu" signal "IN1")
		(8 "In3.Cu" signal "GND1")
		(10 "In4.Cu" signal "IN2")
		(12 "In5.Cu" signal "GND2")
		(14 "In6.Cu" signal "IN3")
		(16 "In7.Cu" signal "GND3")
		(18 "In8.Cu" signal "VCC")
		(20 "In9.Cu" signal "VCC1")
		(22 "In10.Cu" signal "GND4")
		(24 "In11.Cu" signal "IN4")
		(26 "In12.Cu" signal "GND5")
		(28 "In13.Cu" signal "IN5")
		(30 "In14.Cu" signal "GND6")
		(32 "In15.Cu" signal "IN6")
		(34 "In16.Cu" signal "GND7")
		(2 "B.Cu" signal "BOTTOM")
		(9 "F.Adhes" user "F.Adhesive")
		(11 "B.Adhes" user "B.Adhesive")
		(13 "F.Paste" user "Package Geometry/Pastemask Top")
		(15 "B.Paste" user "Package Geometry/Pastemask Bottom")
		(5 "F.SilkS" user "Ref Des/Silkscreen Top")
		(7 "B.SilkS" user "Ref Des/Silkscreen Bottom")
		(1 "F.Mask" user "Board Geometry/Soldermask Top")
		(3 "B.Mask" user "Board Geometry/Soldermask Bottom")
		(17 "Dwgs.User" user "User.Drawings")
		(19 "Cmts.User" user "User.Comments")
		(21 "Eco1.User" user "User.Eco1")
		(23 "Eco2.User" user "User.Eco2")
		(25 "Edge.Cuts" user "Board Geometry/Outline")
		(27 "Margin" user)
		(31 "F.CrtYd" user "Package Geometry/Place Bound Top")
		(29 "B.CrtYd" user "Package Geometry/Place Bound Bottom")
		(35 "F.Fab" user "Ref Des/Assembly Top")
		(33 "B.Fab" user "Ref Des/Assembly Bottom")
	)
	(footprint ""
		(layer "F.Cu")
		(at 332.438248 -402.371052 -90)
		(property "Reference" "C1793"
			(at 0 0 270)
			(layer "F.SilkS")
			(hide yes)
			(effects
				(font
					(size 1.27 1.27)
				)
			)
		)
		(property "Value" ""
			(at 0 0 270)
			(layer "F.Fab")
			(effects
				(font
					(size 1.27 1.27)
				)
			)
		)
		(duplicate_pad_numbers_are_jumpers no)
		(fp_line
			(start -0.299974 0.150114)
			(end -0.299974 -0.150114)
			(stroke
				(width 0.1)
				(type default)
			)
			(layer "F.Fab")
		)
		(fp_line
			(start 0.299974 0.150114)
			(end -0.299974 0.150114)
			(stroke
				(width 0.1)
				(type default)
			)
			(layer "F.Fab")
		)
		(fp_line
			(start -0.299974 -0.150114)
			(end 0.299974 -0.150114)
			(stroke
				(width 0.1)
				(type default)
			)
			(layer "F.Fab")
		)
		(fp_line
			(start 0.299974 -0.150114)
			(end 0.299974 0.150114)
			(stroke
				(width 0.1)
				(type default)
			)
			(layer "F.Fab")
		)
		(pad "1" smd rect
			(at -0.2667 0 270)
			(size 0.3048 0.381)
			(layers "F.Cu" "F.Mask" "F.Paste")
			(net "P5E_CPU0_PE4_TX_C_DP<9>")
		)
		(pad "2" smd rect
			(at 0.2667 0 270)
			(size 0.3048 0.381)
			(layers "F.Cu" "F.Mask" "F.Paste")
			(net "P5E_CPU0_PE4_TX_DP<9>")
		)
	)
	(footprint ""
		(layer "F.Cu")
		(at 217.881962 -67.324478 180)
		(property "Reference" "PR3965"
			(at 0 0 180)
			(layer "F.SilkS")
			(hide yes)
			(effects
				(font
					(size 1.27 1.27)
				)
			)
		)
		(property "Value" ""
			(at 0 0 180)
			(layer "F.Fab")
			(effects
				(font
					(size 1.27 1.27)
				)
			)
		)
		(duplicate_pad_numbers_are_jumpers no)
		(fp_line
			(start 0.7874 0.4064)
			(end -0.7874 0.4064)
			(stroke
				(width 0.1524)
				(type default)
			)
			(layer "F.SilkS")
		)
		(fp_line
			(start 0.7874 -0.4064)
			(end 0.7874 0.4064)
			(stroke
				(width 0.1524)
				(type default)
			)
			(layer "F.SilkS")
		)
		(fp_line
			(start -0.7874 0.4064)
			(end -0.7874 -0.4064)
			(stroke
				(width 0.1524)
				(type default)
			)
			(layer "F.SilkS")
		)
		(fp_line
			(start -0.7874 -0.4064)
			(end 0.7874 -0.4064)
			(stroke
				(width 0.1524)
				(type default)
			)
			(layer "F.SilkS")
		)
		(fp_line
			(start 0.67945 0.3048)
			(end 0.120396 0.3048)
			(stroke
				(width 0.1)
				(type default)
			)
			(layer "F.Fab")
		)
		(fp_line
			(start 0.67945 -0.3048)
			(end 0.67945 0.3048)
			(stroke
				(width 0.1)
				(type default)
			)
			(layer "F.Fab")
		)
		(fp_line
			(start 0.12065 -0.2794)
			(end 0.12065 -0.3048)
			(stroke
				(width 0.1)
				(type default)
			)
			(layer "F.Fab")
		)
		(fp_line
			(start 0.12065 -0.3048)
			(end 0.67945 -0.3048)
			(stroke
				(width 0.1)
				(type default)
			)
			(layer "F.Fab")
		)
		(fp_line
			(start 0.120396 0.3048)
			(end 0.120396 0.2794)
			(stroke
				(width 0.1)
				(type default)
			)
			(layer "F.Fab")
		)
		(fp_line
			(start 0.120396 0.2794)
			(end -0.12065 0.2794)
			(stroke
				(width 0.1)
				(type default)
			)
			(layer "F.Fab")
		)
		(fp_line
			(start -0.12065 0.3048)
			(end -0.67945 0.3048)
			(stroke
				(width 0.1)
				(type default)
			)
			(layer "F.Fab")
		)
		(fp_line
			(start -0.12065 0.2794)
			(end -0.12065 0.3048)
			(stroke
				(width 0.1)
				(type default)
			)
			(layer "F.Fab")
		)
		(fp_line
			(start -0.12065 -0.2794)
			(end 0.12065 -0.2794)
			(stroke
				(width 0.1)
				(type default)
			)
			(layer "F.Fab")
		)
		(fp_line
			(start -0.12065 -0.305054)
			(end -0.12065 -0.2794)
			(stroke
				(width 0.1)
				(type default)
			)
			(layer "F.Fab")
		)
		(fp_line
			(start -0.67945 0.3048)
			(end -0.67945 -0.305054)
			(stroke
				(width 0.1)
				(type default)
			)
			(layer "F.Fab")
		)
		(fp_line
			(start -0.67945 -0.305054)
			(end -0.12065 -0.305054)
			(stroke
				(width 0.1)
				(type default)
			)
			(layer "F.Fab")
		)
		(pad "1" smd circle
			(at -0.40005 0 180)
			(size 0 0)
			(layers "F.Cu" "F.Mask" "F.Paste")
			(net "P3V3_E1S_OV_0")
		)
		(pad "2" smd circle
			(at 0.40005 0 180)
			(size 0 0)
			(layers "F.Cu" "F.Mask" "F.Paste")
			(net "GND")
		)
	)
	(footprint ""
		(layer "F.Cu")
		(at 211.455 -68.253356 -90)
		(property "Reference" "R4710"
			(at 0 0 270)
			(layer "F.SilkS")
			(hide yes)
			(effects
				(font
					(size 1.27 1.27)
				)
			)
		)
		(property "Value" ""
			(at 0 0 270)
			(layer "F.Fab")
			(effects
				(font
					(size 1.27 1.27)
				)
			)
		)
		(duplicate_pad_numbers_are_jumpers no)
		(fp_line
			(start -0.7874 0.4064)
			(end -0.7874 -0.4064)
			(stroke
				(width 0.1524)
				(type default)
			)
			(layer "F.SilkS")
		)
		(fp_line
			(start 0.7874 0.4064)
			(end -0.7874 0.4064)
			(stroke
				(width 0.1524)
				(type default)
			)
			(layer "F.SilkS")
		)
		(fp_line
			(start -0.7874 -0.4064)
			(end 0.7874 -0.4064)
			(stroke
				(width 0.1524)
				(type default)
			)
			(layer "F.SilkS")
		)
		(fp_line
			(start 0.7874 -0.4064)
			(end 0.7874 0.4064)
			(stroke
				(width 0.1524)
				(type default)
			)
			(layer "F.SilkS")
		)
		(fp_line
			(start -0.67945 0.3048)
			(end -0.67945 -0.305054)
			(stroke
				(width 0.1)
				(type default)
			)
			(layer "F.Fab")
		)
		(fp_line
			(start -0.12065 0.3048)
			(end -0.67945 0.3048)
			(stroke
				(width 0.1)
				(type default)
			)
			(layer "F.Fab")
		)
		(fp_line
			(start 0.120396 0.3048)
			(end 0.120396 0.2794)
			(stroke
				(width 0.1)
				(type default)
			)
			(layer "F.Fab")
		)
		(fp_line
			(start 0.67945 0.3048)
			(end 0.120396 0.3048)
			(stroke
				(width 0.1)
				(type default)
			)
			(layer "F.Fab")
		)
		(fp_line
			(start -0.12065 0.2794)
			(end -0.12065 0.3048)
			(stroke
				(width 0.1)
				(type default)
			)
			(layer "F.Fab")
		)
		(fp_line
			(start 0.120396 0.2794)
			(end -0.12065 0.2794)
			(stroke
				(width 0.1)
				(type default)
			)
			(layer "F.Fab")
		)
		(fp_line
			(start -0.12065 -0.2794)
			(end 0.12065 -0.2794)
			(stroke
				(width 0.1)
				(type default)
			)
			(layer "F.Fab")
		)
		(fp_line
			(start 0.12065 -0.2794)
			(end 0.12065 -0.3048)
			(stroke
				(width 0.1)
				(type default)
			)
			(layer "F.Fab")
		)
		(fp_line
			(start 0.12065 -0.3048)
			(end 0.67945 -0.3048)
			(stroke
				(width 0.1)
				(type default)
			)
			(layer "F.Fab")
		)
		(fp_line
			(start 0.67945 -0.3048)
			(end 0.67945 0.3048)
			(stroke
				(width 0.1)
				(type default)
			)
			(layer "F.Fab")
		)
		(fp_line
			(start -0.67945 -0.305054)
			(end -0.12065 -0.305054)
			(stroke
				(width 0.1)
				(type default)
			)
			(layer "F.Fab")
		)
		(fp_line
			(start -0.12065 -0.305054)
			(end -0.12065 -0.2794)
			(stroke
				(width 0.1)
				(type default)
			)
			(layer "F.Fab")
		)
		(pad "1" smd circle
			(at -0.40005 0 270)
			(size 0 0)
			(layers "F.Cu" "F.Mask" "F.Paste")
			(net "P3V3_AUX")
		)
		(pad "2" smd circle
			(at 0.40005 0 270)
			(size 0 0)
			(layers "F.Cu" "F.Mask" "F.Paste")
			(net "LED_P12V_SCM_FAULT_D1")
		)
	)
)
